# BASEBOARD_FAB2 (Tioga Pass) — schematic netlist excerpt (pin names and nets, part order shuffled) for the footprints in the layout excerpt that follows; sources: Cadence DE-HDL packaged netlist, KiCad conversion of Wiwynn_Tioga_Pass_MB.brd

R2T13  RES  200.0 1% CHIP  pkg 0402  page 154 : A = SPI_CS0_PRIMARY_N ; B = SPI_CS0_PRIMARY_R_N
R6P25  RES  2.2 1.0% CHIP  pkg 0603  page 102 : A = P3V3_DB1200 ; B = P3V3_DB1200_R
C9L6  CAP  10UF 16V 10% X6S  pkg 0805  page 227 : A = VR_FET_SW_P12V_STBY_PVDDQ_KLM ; B = GND

(kicad_pcb
	(version 20260206)
	(generator "pcbnew")
	(generator_version "10.0")
	(general
		(thickness 1.6)
		(legacy_teardrops no)
	)
	(paper "A4")
	(title_block
		(title "Wiwynn_Tioga_Pass_MB.brd")
		(comment 1 "Tioga Pass / footprints 3311-3313 of 4770")
	)
	(layers
		(0 "F.Cu" signal "TOP")
		(4 "In1.Cu" signal "L2GND")
		(6 "In2.Cu" signal "L3")
		(8 "In3.Cu" signal "L4GND")
		(10 "In4.Cu" signal "L5")
		(12 "In5.Cu" signal "L6GND")
		(14 "In6.Cu" signal "L7VCC")
		(16 "In7.Cu" signal "L8VCC")
		(18 "In8.Cu" signal "L9GND")
		(20 "In9.Cu" signal "L10")
		(22 "In10.Cu" signal "L11GND")
		(24 "In11.Cu" signal "L12")
		(26 "In12.Cu" signal "L13GND")
		(2 "B.Cu" signal "BOTTOM")
		(9 "F.Adhes" user "F.Adhesive")
		(11 "B.Adhes" user "B.Adhesive")
		(13 "F.Paste" user "Package Geometry/Pastemask Top")
		(15 "B.Paste" user "Package Geometry/Pastemask Bottom")
		(5 "F.SilkS" user "Ref Des/Silkscreen Top")
		(7 "B.SilkS" user "Ref Des/Silkscreen Bottom")
		(1 "F.Mask" user "Board Geometry/Soldermask Top")
		(3 "B.Mask" user "Board Geometry/Soldermask Bottom")
		(17 "Dwgs.User" user "User.Drawings")
		(19 "Cmts.User" user "User.Comments")
		(21 "Eco1.User" user "User.Eco1")
		(23 "Eco2.User" user "User.Eco2")
		(25 "Edge.Cuts" user "Board Geometry/Outline")
		(27 "Margin" user)
		(31 "F.CrtYd" user "Package Geometry/Place Bound Top")
		(29 "B.CrtYd" user "Package Geometry/Place Bound Bottom")
		(35 "F.Fab" user "Ref Des/Assembly Top")
		(33 "B.Fab" user "Ref Des/Assembly Bottom")
	)
	(footprint ""
		(layer "B.Cu")
		(at 394.337032 -66.273172 90)
		(property "Reference" "R2T13"
			(at 0 0 90)
			(layer "B.SilkS")
			(hide yes)
			(effects
				(font
					(size 1.27 1.27)
				)
				(justify mirror)
			)
		)
		(property "Value" ""
			(at 0 0 90)
			(layer "B.Fab")
			(effects
				(font
					(size 1.27 1.27)
				)
				(justify mirror)
			)
		)
		(duplicate_pad_numbers_are_jumpers no)
		(fp_poly
			(pts
				(xy 0.2794 -0.1016) (xy -0.2794 -0.1016) (xy -0.2794 0.9906) (xy 0.2794 0.9906)
			)
			(stroke
				(width 0)
				(type default)
			)
			(fill no)
			(layer "B.CrtYd")
		)
		(fp_line
			(start 0.2794 -0.1016)
			(end 0.2794 0.9906)
			(stroke
				(width 0.1)
				(type default)
			)
			(layer "B.Fab")
		)
		(fp_line
			(start -0.2794 -0.1016)
			(end 0.2794 -0.1016)
			(stroke
				(width 0.1)
				(type default)
			)
			(layer "B.Fab")
		)
		(fp_line
			(start 0.2794 0.9906)
			(end -0.2794 0.9906)
			(stroke
				(width 0.1)
				(type default)
			)
			(layer "B.Fab")
		)
		(fp_line
			(start -0.2794 0.9906)
			(end -0.2794 -0.1016)
			(stroke
				(width 0.1)
				(type default)
			)
			(layer "B.Fab")
		)
		(pad "1" smd rect
			(at 0 0 270)
			(size 0.508 0.508)
			(layers "B.Cu" "B.Mask" "B.Paste")
			(net "SPI_CS0_PRIMARY_N")
		)
		(pad "2" smd rect
			(at 0 0.889 270)
			(size 0.508 0.508)
			(layers "B.Cu" "B.Mask" "B.Paste")
			(net "SPI_CS0_PRIMARY_R_N")
		)
		(zone
			(layer "B.Cu")
			(hatch none 0.5)
			(connect_pads
				(clearance 0)
			)
			(min_thickness 0.25)
			(keepout
				(tracks allowed)
				(vias not_allowed)
				(pads allowed)
				(copperpour not_allowed)
				(footprints allowed)
			)
			(placement
				(enabled no)
				(sheetname "")
			)
			(fill
				(thermal_gap 0.5)
				(thermal_bridge_width 0.5)
				(island_removal_mode 0)
			)
			(polygon
				(pts
					(xy 394.591032 -66.527172) (xy 394.591032 -66.019172) (xy 394.972032 -66.019172) (xy 394.972032 -66.527172)
				)
			)
		)
		(zone
			(layer "B.Cu")
			(hatch none 0.5)
			(connect_pads
				(clearance 0)
			)
			(min_thickness 0.25)
			(keepout
				(tracks not_allowed)
				(vias allowed)
				(pads allowed)
				(copperpour not_allowed)
				(footprints allowed)
			)
			(placement
				(enabled no)
				(sheetname "")
			)
			(fill
				(thermal_gap 0.5)
				(thermal_bridge_width 0.5)
				(island_removal_mode 0)
			)
			(polygon
				(pts
					(xy 394.972032 -66.527172) (xy 394.972032 -66.019172) (xy 394.591032 -66.019172) (xy 394.591032 -66.527172)
				)
			)
		)
	)
	(footprint ""
		(layer "B.Cu")
		(at 169.545 -73.4822 180)
		(property "Reference" "R6P25"
			(at 0 0 0)
			(layer "B.SilkS")
			(hide yes)
			(effects
				(font
					(size 1.27 1.27)
				)
				(justify mirror)
			)
		)
		(property "Value" ""
			(at 0 0 0)
			(layer "B.Fab")
			(effects
				(font
					(size 1.27 1.27)
				)
				(justify mirror)
			)
		)
		(duplicate_pad_numbers_are_jumpers no)
		(fp_poly
			(pts
				(xy 0.4953 -0.2032) (xy -0.4953 -0.2032) (xy -0.4953 1.6002) (xy 0.4953 1.6002)
			)
			(stroke
				(width 0)
				(type default)
			)
			(fill no)
			(layer "B.CrtYd")
		)
		(fp_line
			(start 0.4953 1.6002)
			(end 0.4953 -0.2032)
			(stroke
				(width 0.1)
				(type default)
			)
			(layer "B.Fab")
		)
		(fp_line
			(start 0.4953 -0.2032)
			(end -0.4953 -0.2032)
			(stroke
				(width 0.1)
				(type default)
			)
			(layer "B.Fab")
		)
		(fp_line
			(start -0.4953 1.6002)
			(end 0.4953 1.6002)
			(stroke
				(width 0.1)
				(type default)
			)
			(layer "B.Fab")
		)
		(fp_line
			(start -0.4953 -0.2032)
			(end -0.4953 1.6002)
			(stroke
				(width 0.1)
				(type default)
			)
			(layer "B.Fab")
		)
		(pad "1" smd rect
			(at 0 0)
			(size 0.762 0.889)
			(layers "B.Cu" "B.Mask" "B.Paste")
			(net "P3V3_DB1200")
		)
		(pad "2" smd rect
			(at 0 1.397)
			(size 0.762 0.889)
			(layers "B.Cu" "B.Mask" "B.Paste")
			(net "P3V3_DB1200_R")
		)
		(zone
			(layer "B.Cu")
			(hatch none 0.5)
			(connect_pads
				(clearance 0)
			)
			(min_thickness 0.25)
			(keepout
				(tracks not_allowed)
				(vias allowed)
				(pads allowed)
				(copperpour not_allowed)
				(footprints allowed)
			)
			(placement
				(enabled no)
				(sheetname "")
			)
			(fill
				(thermal_gap 0.5)
				(thermal_bridge_width 0.5)
				(island_removal_mode 0)
			)
			(polygon
				(pts
					(xy 169.164 -74.4347) (xy 169.164 -73.9267) (xy 169.926 -73.9267) (xy 169.926 -74.4347)
				)
			)
		)
		(zone
			(layer "B.Cu")
			(hatch none 0.5)
			(connect_pads
				(clearance 0)
			)
			(min_thickness 0.25)
			(keepout
				(tracks allowed)
				(vias not_allowed)
				(pads allowed)
				(copperpour not_allowed)
				(footprints allowed)
			)
			(placement
				(enabled no)
				(sheetname "")
			)
			(fill
				(thermal_gap 0.5)
				(thermal_bridge_width 0.5)
				(island_removal_mode 0)
			)
			(polygon
				(pts
					(xy 169.926 -74.4347) (xy 169.926 -73.9267) (xy 169.164 -73.9267) (xy 169.164 -74.4347)
				)
			)
		)
	)
	(footprint ""
		(layer "B.Cu")
		(at 1.3462 -139.446 90)
		(property "Reference" "C9L6"
			(at 0 0 90)
			(layer "B.SilkS")
			(hide yes)
			(effects
				(font
					(size 1.27 1.27)
				)
				(justify mirror)
			)
		)
		(property "Value" ""
			(at 0 0 90)
			(layer "B.Fab")
			(effects
				(font
					(size 1.27 1.27)
				)
				(justify mirror)
			)
		)
		(duplicate_pad_numbers_are_jumpers no)
		(fp_rect
			(start -0.7239 -0.2159)
			(end 0.7239 1.9939)
			(stroke
				(width 0)
				(type default)
			)
			(fill no)
			(layer "B.CrtYd")
		)
		(fp_line
			(start 0.7239 -0.2159)
			(end 0.7239 1.9939)
			(stroke
				(width 0.1)
				(type default)
			)
			(layer "B.Fab")
		)
		(fp_line
			(start -0.7239 -0.2159)
			(end 0.7239 -0.2159)
			(stroke
				(width 0.1)
				(type default)
			)
			(layer "B.Fab")
		)
		(fp_line
			(start 0.7239 1.9939)
			(end -0.7239 1.9939)
			(stroke
				(width 0.1)
				(type default)
			)
			(layer "B.Fab")
		)
		(fp_line
			(start -0.7239 1.9939)
			(end -0.7239 -0.2159)
			(stroke
				(width 0.1)
				(type default)
			)
			(layer "B.Fab")
		)
		(pad "1" smd rect
			(at 0 0 270)
			(size 1.27 1.016)
			(layers "B.Cu" "B.Mask" "B.Paste")
			(net "VR_FET_SW_P12V_STBY_PVDDQ_KLM")
		)
		(pad "2" smd rect
			(at 0 1.778 270)
			(size 1.27 1.016)
			(layers "B.Cu" "B.Mask" "B.Paste")
			(net "GND")
		)
		(zone
			(layer "B.Cu")
			(hatch none 0.5)
			(connect_pads
				(clearance 0)
			)
			(min_thickness 0.25)
			(keepout
				(tracks not_allowed)
				(vias allowed)
				(pads allowed)
				(copperpour not_allowed)
				(footprints allowed)
			)
			(placement
				(enabled no)
				(sheetname "")
			)
			(fill
				(thermal_gap 0.5)
				(thermal_bridge_width 0.5)
				(island_removal_mode 0)
			)
			(polygon
				(pts
					(xy 1.8542 -138.811) (xy 2.6162 -138.811) (xy 2.6162 -140.081) (xy 1.8542 -140.081)
				)
			)
		)
	)
)
